%FSTAX25Y25*%
%MOIN*%
%SFA1B1*%

%IPPOS*%
%ADD10C,0.008000*%
%ADD14C,0.010000*%
%ADD18C,0.006000*%
%ADD22C,0.005000*%
%ADD147C,0.020000*%
%ADD155C,0.075000*%
%ADD162C,0.055000*%
%ADD163R,0.055000X0.055000*%
%ADD165C,0.016000*%
%LNgrandmaster-1*%
%LPD*%
G54D10*
X09264Y08609D02*
X09268Y08605D01*
X08265Y0651D02*
Y0729028D01*
X0826219Y0729309D02*
X08265Y0729028D01*
X0826219Y0729309D02*
Y0746781D01*
X082425Y076175D02*
X0825Y07625D01*
X0931933Y0683D02*
Y0694067D01*
X09315Y06945D02*
X0931933Y0694067D01*
X0942941Y0687488D02*
Y0687873D01*
X0942907Y0687907D02*
X0942941Y0687873D01*
X0754Y0746922D02*
X0755836Y0745086D01*
Y0707164D02*
Y0745086D01*
X08437Y0727984D02*
X08441Y0728383D01*
X08437Y06441D02*
Y0727984D01*
X08441Y0728383D02*
Y07286D01*
X09592Y07896D02*
Y08142D01*
X11568Y07218D02*
X1156831Y0721831D01*
Y0749298*
X08685Y0728831D02*
X08693Y0729631D01*
Y07297*
X08685Y06485D02*
Y0728831D01*
X0838Y0742928D02*
Y08485D01*
X08375Y0742428D02*
X0838Y0742928D01*
X08375Y0740772D02*
Y0742428D01*
Y0740772D02*
X0838Y0740272D01*
Y0695217D02*
Y0740272D01*
X08375Y0694717D02*
X0838Y0695217D01*
X08375Y06945D02*
Y0694717D01*
X09735Y06715D02*
Y08265D01*
Y06715D02*
X09765Y06685D01*
Y0667102D02*
Y06685D01*
X0976402Y0667004D02*
X09765Y0667102D01*
X11625Y0595125D02*
Y0724D01*
X1156831Y0589456D02*
X11625Y0595125D01*
X08615Y0678166D02*
Y07465D01*
X0861547Y0677553D02*
X08617Y06774D01*
X0861547Y0677553D02*
Y0678119D01*
X08615Y0678166D02*
X0861547Y0678119D01*
X09911Y08106D02*
X0993Y08125D01*
X09911Y0668914D02*
Y08106D01*
Y0668914D02*
X09915Y0668513D01*
Y0654D02*
Y0668513D01*
X0918742Y06718D02*
Y0797342D01*
X09188Y07974*
X08595Y06738D02*
Y0743531D01*
X08245Y0854D02*
X0829Y08495D01*
Y0692D02*
Y08495D01*
X0857Y06794D02*
Y07285D01*
X0825Y07625D02*
Y08265D01*
X09365Y0827483D02*
Y08277D01*
X09359Y0826884D02*
X09365Y0827483D01*
X09359Y08054D02*
Y0826884D01*
X1003Y0741D02*
X1005256Y0743256D01*
Y0759928*
X0854Y06759D02*
Y08325D01*
X08625Y0841*
X09268Y06809D02*
Y08605D01*
X09264Y08609D02*
X09265Y0861D01*
X0978Y08239D02*
X09797D01*
X0976Y08219D02*
X0978Y08239D01*
X0976Y0673D02*
Y08219D01*
Y0673D02*
X09794Y06696D01*
Y06695D02*
Y06696D01*
X0803Y09256D02*
X0857Y08716D01*
Y0849D02*
Y08716D01*
X0803Y09056D02*
X08196Y0889D01*
Y08204D02*
Y0889D01*
X07429Y0905681D02*
Y09064D01*
Y0905681D02*
X07451Y0903481D01*
Y0855272D02*
Y0903481D01*
X0745Y0855172D02*
X07451Y0855272D01*
X0745Y08151D02*
Y0855172D01*
X07371Y09206D02*
X07429Y09264D01*
X07371Y08621D02*
Y09206D01*
Y08621D02*
X07431Y08561D01*
X09483Y07361D02*
Y083D01*
X09613Y07592D02*
Y0849D01*
Y07592D02*
X09614Y07591D01*
X09385Y07015D02*
Y08451D01*
X09482Y08301D02*
X09483Y083D01*
X095Y0832772D02*
Y0877086D01*
Y0832772D02*
X09515Y0831272D01*
Y0647D02*
Y0831272D01*
X095Y0877086D02*
X0951Y0878086D01*
Y09075*
X09495Y0909D02*
X0951Y09075D01*
X0953504Y0745997D02*
Y0832096D01*
X0953302Y0832298D02*
X0953504Y0832096D01*
X09335Y08D02*
Y0829072D01*
Y07269D02*
Y08D01*
X09644Y08297D02*
X09678D01*
X0968116Y0829385*
X09427Y07003D02*
Y08461D01*
Y07003D02*
X0943Y07D01*
X09483Y07361D02*
X09492Y07352D01*
X09488Y07348D02*
X09492Y07352D01*
X09335Y0829072D02*
X09349Y0830472D01*
Y08452*
X09293Y0698116D02*
Y08348D01*
X09289Y0697717D02*
X09293Y0698116D01*
X09289Y06975D02*
Y0697717D01*
X09825Y06485D02*
Y0732534D01*
X0979Y0736033D02*
X09825Y0732534D01*
X098305Y0786533D02*
X09845Y0787983D01*
X098305Y0737246D02*
Y0786533D01*
Y0737246D02*
X09885Y0731796D01*
X0979Y0736033D02*
Y08205D01*
X098145Y0736584D02*
X09855Y0732534D01*
Y06515D02*
Y0732534D01*
X0968116Y0670885D02*
Y0829385D01*
X09315Y06945D02*
X09385Y07015D01*
X09215Y0666528D02*
Y08233D01*
X09221Y08239*
X09595Y0709394D02*
X09604Y0708494D01*
X09595Y0709394D02*
Y0740001D01*
X09604Y06739D02*
Y0708494D01*
X0958Y06715D02*
X09604Y06739D01*
X0953504Y0745997D02*
X09595Y0740001D01*
X09488Y07348D02*
X0949Y07346D01*
X09489Y07345D02*
X0949Y07346D01*
X08469Y05941D02*
Y07292D01*
X08466Y07295D02*
X08469Y07292D01*
X0897Y0797557D02*
X08999Y0800457D01*
X08989Y0797618D02*
X09012Y0799918D01*
Y0882584*
X0897Y0746407D02*
Y0797557D01*
X08999Y0800457D02*
Y0839014D01*
X08989Y0762224D02*
Y0797618D01*
X09005Y0883284D02*
X09012Y0882584D01*
X09005Y0883284D02*
Y08835D01*
X0900352Y0731852D02*
Y0760773D01*
X08989Y0762224D02*
X0900352Y0760773D01*
X08976Y07291D02*
X0900352Y0731852D01*
X0957Y0759D02*
Y07947D01*
X09243Y06665D02*
Y08297D01*
X08196Y06303D02*
Y0741289D01*
Y06303D02*
X08197Y06302D01*
X08196Y0747205D02*
Y08204D01*
Y0747205D02*
X0821612Y0745193D01*
Y0743301D02*
Y0745193D01*
X08196Y0741289D02*
X0821612Y0743301D01*
X0822Y0759D02*
Y0850284D01*
X08225Y0850784*
Y0851*
X0843946Y0764511D02*
Y0845554D01*
X0841935Y07625D02*
X0843946Y0764511D01*
X08425Y0847D02*
X0843946Y0845554D01*
X08493Y0632D02*
Y0721472D01*
X08496Y0744672D02*
Y0764772D01*
X08516Y0764933D02*
X08518Y0765133D01*
X0851Y0723172D02*
Y0743272D01*
X08496Y0744672D02*
X0851Y0743272D01*
X08496Y0764772D02*
X08505Y0765672D01*
X08516Y07467D02*
Y0764933D01*
X08493Y0772028D02*
X08505Y0770828D01*
X08493Y0772028D02*
Y0808183D01*
X08495Y0808383D02*
Y08086D01*
X08518Y08438D02*
X0857Y0849D01*
X08518Y0765133D02*
Y08438D01*
X08493Y0721472D02*
X0851Y0723172D01*
X08505Y0765672D02*
Y0770828D01*
X08493Y0808183D02*
X08495Y0808383D01*
X08425Y0847D02*
Y0855D01*
X08911Y06541D02*
Y07432D01*
X0891Y0654D02*
X08911Y06541D01*
X08933Y0729D02*
X0894572D01*
X0895786Y0730214*
Y0745193*
X0897Y0746407*
X09333Y07267D02*
X09335Y07269D01*
X084Y06971D02*
Y07287D01*
X08634Y06715D02*
X08639Y0672D01*
X08634Y0662D02*
Y06715D01*
X08639Y0672D02*
Y0726934D01*
X08636Y07278D02*
X0863753Y0727647D01*
Y0727081D02*
Y0727647D01*
Y0727081D02*
X08639Y0726934D01*
X08656Y06645D02*
X08657Y06644D01*
X08656Y06645D02*
Y07295D01*
X08717Y0660369D02*
Y07297D01*
X0871Y0659669D02*
X08717Y0660369D01*
X0871Y06595D02*
Y0659669D01*
X07875Y07075D02*
Y08605D01*
X08019Y063656D02*
X0802Y063666D01*
Y0884*
X07995Y0634D02*
Y0882D01*
X0805Y0639D02*
Y08875D01*
X07745Y0713D02*
Y08665D01*
X0754Y0746922D02*
Y08625D01*
X07565Y0746684D02*
X0761Y0742184D01*
X07565Y0746684D02*
Y086D01*
X0761Y07125D02*
Y0742184D01*
X0771Y0654D02*
X0777Y066D01*
Y0916*
X09515Y0647D02*
X0954Y06445D01*
X0898354Y0840559D02*
Y08755D01*
Y0840559D02*
X08999Y0839014D01*
X08885Y06565D02*
Y07435D01*
X09885Y0657D02*
Y0731796D01*
X09711Y06679D02*
X09715D01*
X0968116Y0670885D02*
X09711Y06679D01*
X0942907Y0687907D02*
X0946Y0691D01*
X09845Y0787983D02*
Y08155D01*
X0982Y0787746D02*
Y0818D01*
X098145Y0736584D02*
Y0787196D01*
X0982Y0787746*
X09383Y06953D02*
X0943Y07D01*
X09383Y06875D02*
Y06953D01*
X0946Y0691D02*
Y0846D01*
G54D14*
X08716Y08164D02*
Y08328D01*
X08717Y08329*
G54D18*
X08074Y064156D02*
X080745Y064161D01*
Y088995*
X08075Y089*
G54D22*
X08845Y05399D02*
D01*
X0884613Y0540022*
X0884718Y0540151*
X0884814Y0540288*
X08849Y0540431*
X0884976Y0540579*
X0885041Y0540733*
X0885095Y0540891*
X0885138Y0541052*
X088517Y0541216*
X088519Y0541381*
X0885199Y0541548*
X08852Y054159*
X0881568Y0539665D02*
D01*
X0881526Y0539703*
X0881483Y0539738*
X0881437Y053977*
X0881389Y0539799*
X0881339Y0539825*
X0881287Y0539846*
X0881234Y0539865*
X088118Y0539879*
X0881125Y053989*
X088107Y0539897*
X0881014Y05399*
X0881Y05399*
X088307Y0538163D02*
D01*
X0883194Y0538067*
X0883325Y053798*
X0883462Y0537903*
X0883604Y0537836*
X088375Y0537778*
X08839Y0537731*
X0884052Y0537694*
X0884207Y0537669*
X0884364Y0537654*
X0884521Y053765*
X0884677Y0537657*
X0884833Y0537675*
X0884988Y0537703*
X088514Y0537743*
X0885289Y0537793*
X0885434Y0537853*
X0885574Y0537923*
X088571Y0538003*
X0885839Y0538092*
X0885962Y053819*
X0886078Y0538296*
X0886186Y053841*
X0886285Y0538531*
X0886376Y0538659*
X0886458Y0538793*
X0886531Y0538932*
X0886593Y0539076*
X0886646Y0539224*
X0886688Y0539376*
X0886719Y053953*
X0886739Y0539685*
X0886749Y0539842*
X0886747Y0539999*
X0886735Y0540156*
X0886711Y0540311*
X0886677Y0540464*
X0886633Y0540615*
X0886578Y0540762*
X0886522Y0540886*
X0882776Y0538454D02*
D01*
X0882752Y0538479*
X0882745Y0538488*
X0882776Y0538454D02*
D01*
X0882881Y0538337*
X0882994Y0538228*
X088307Y0538163*
X0886475Y0541163D02*
D01*
X0886495Y0541419*
X08865Y054159*
X0886475Y0541163D02*
D01*
X0886472Y0541128*
X0886471Y0541093*
X0886473Y0541058*
X0886478Y0541023*
X0886485Y0540989*
X0886494Y0540955*
X0886505Y0540922*
X0886519Y054089*
X0886522Y0540886*
X0886723Y0580744D02*
D01*
X0886698Y0580719*
X0886675Y0580693*
X0886653Y0580665*
X0886634Y0580636*
X0886617Y0580606*
X0886602Y0580574*
X0886589Y0580542*
X0886589Y0580538*
D01*
X0886575Y0580497*
X0886561Y0580457*
X0886548Y0580417*
X0886535Y0580377*
X0886523Y0580337*
D01*
X0886513Y0580303*
X0886506Y0580269*
X0886502Y0580234*
X08865Y0580199*
X08865Y0580188*
X0886723Y0580744D02*
D01*
X0886834Y0580854*
X0886938Y0580972*
X0887034Y0581096*
X088712Y0581227*
X0887197Y0581364*
X0887264Y0581506*
X0887322Y0581652*
X0887369Y0581802*
X0887405Y0581955*
X0887431Y058211*
X0887433Y0582121*
X0887522Y058235D02*
D01*
X0887502Y058232*
X0887485Y058229*
X088747Y0582259*
X0887457Y0582226*
X0887447Y0582193*
X0887438Y0582159*
X0887433Y0582124*
Y0582121*
X0888285Y0583251D02*
D01*
X0887946Y0582887*
X0887633Y0582501*
X0887522Y058235*
X088445Y055009D02*
D01*
X0884502Y0550091*
X0884554Y0550097*
X0884605Y0550106*
X0884656Y0550119*
X0884706Y0550135*
X0884755Y0550154*
X0884802Y0550177*
X0884847Y0550203*
X088489Y0550233*
X0884932Y0550265*
X088497Y05503*
X0885007Y0550338*
X0885041Y0550378*
X0885071Y055042*
X0885099Y0550465*
X0885124Y0550511*
X0885145Y0550559*
X0885163Y0550608*
X0885177Y0550658*
X0885188Y0550709*
X0885195Y0550761*
X0885199Y0550813*
X08852Y055084*
X088415Y055009D02*
D01*
X0884097Y0550088*
X0884045Y0550082*
X0883994Y0550073*
X0883943Y055006*
X0883893Y0550044*
X0883844Y0550025*
X0883797Y0550002*
X0883752Y0549976*
X0883709Y0549946*
X0883667Y0549914*
X0883629Y0549879*
X0883592Y0549841*
X0883558Y0549801*
X0883528Y0549759*
X08835Y0549715*
X0883475Y0549668*
X0883454Y054962*
X0883436Y0549571*
X0883422Y0549521*
X0883411Y054947*
X0883404Y0549418*
X08834Y0549366*
Y0549313*
X0883404Y0549261*
X0883411Y0549209*
X0883422Y0549158*
X0883436Y0549108*
X0883454Y0549059*
X0883475Y0549011*
X08835Y0548965*
X0883528Y054892*
X0883558Y0548878*
X0883592Y0548838*
X0883629Y05488*
X0883667Y0548765*
X0883709Y0548733*
X0883752Y0548703*
X0883797Y0548677*
X0883844Y0548654*
X0883893Y0548635*
X0883943Y0548619*
X0883994Y0548606*
X0884045Y0548597*
X0884097Y0548591*
X088415Y054859*
X088445Y054709D02*
D01*
X0884502Y0547091*
X0884554Y0547097*
X0884605Y0547106*
X0884656Y0547119*
X0884706Y0547135*
X0884755Y0547154*
X0884802Y0547177*
X0884847Y0547203*
X088489Y0547233*
X0884932Y0547265*
X088497Y05473*
X0885007Y0547338*
X0885041Y0547378*
X0885071Y054742*
X0885099Y0547465*
X0885124Y0547511*
X0885145Y0547559*
X0885163Y0547608*
X0885177Y0547658*
X0885188Y0547709*
X0885195Y0547761*
X0885199Y0547813*
Y0547866*
X0885195Y0547918*
X0885188Y054797*
X0885177Y0548021*
X0885163Y0548071*
X0885145Y054812*
X0885124Y0548168*
X0885099Y0548215*
X0885071Y0548259*
X0885041Y0548301*
X0885007Y0548341*
X088497Y0548379*
X0884932Y0548414*
X088489Y0548446*
X0884847Y0548476*
X0884802Y0548502*
X0884755Y0548525*
X0884706Y0548544*
X0884656Y054856*
X0884605Y0548573*
X0884554Y0548582*
X0884502Y0548588*
X088445Y054859*
X0883713Y054709D02*
D01*
X088366Y0547088*
X0883608Y0547082*
X0883557Y0547073*
X0883506Y054706*
X0883456Y0547044*
X0883407Y0547025*
X088336Y0547002*
X0883315Y0546976*
X0883272Y0546946*
X088323Y0546914*
X0883192Y0546879*
X0883155Y0546841*
X0883121Y0546801*
X0883091Y0546759*
X0883063Y0546715*
X0883038Y0546668*
X0883017Y054662*
X0882999Y0546571*
X0882985Y0546521*
X0882974Y054647*
X0882967Y0546418*
X0882963Y0546366*
Y0546313*
X0882967Y0546261*
X0882974Y0546209*
X0882985Y0546158*
X0882999Y0546108*
X0883017Y0546059*
X0883038Y0546011*
X0883063Y0545965*
X0883091Y054592*
X0883121Y0545878*
X0883155Y0545838*
X0883192Y05458*
X088323Y0545765*
X0883272Y0545733*
X0883315Y0545703*
X088336Y0545677*
X0883407Y0545654*
X0883456Y0545635*
X0883506Y0545619*
X0883557Y0545606*
X0883608Y0545597*
X088366Y0545591*
X0883713Y054559*
X088445Y054409D02*
D01*
X0884502Y0544091*
X0884554Y0544097*
X0884605Y0544106*
X0884656Y0544119*
X0884706Y0544135*
X0884755Y0544154*
X0884802Y0544177*
X0884847Y0544203*
X088489Y0544233*
X0884932Y0544265*
X088497Y05443*
X0885007Y0544338*
X0885041Y0544378*
X0885071Y054442*
X0885099Y0544465*
X0885124Y0544511*
X0885145Y0544559*
X0885163Y0544608*
X0885177Y0544658*
X0885188Y0544709*
X0885195Y0544761*
X0885199Y0544813*
Y0544866*
X0885195Y0544918*
X0885188Y054497*
X0885177Y0545021*
X0885163Y0545071*
X0885145Y054512*
X0885124Y0545168*
X0885099Y0545215*
X0885071Y0545259*
X0885041Y0545301*
X0885007Y0545341*
X088497Y0545379*
X0884932Y0545414*
X088489Y0545446*
X0884847Y0545476*
X0884802Y0545502*
X0884755Y0545525*
X0884706Y0545544*
X0884656Y054556*
X0884605Y0545573*
X0884554Y0545582*
X0884502Y0545588*
X088445Y054559*
X0883713Y054409D02*
D01*
X088366Y0544088*
X0883608Y0544082*
X0883557Y0544073*
X0883506Y054406*
X0883456Y0544044*
X0883407Y0544025*
X088336Y0544002*
X0883315Y0543976*
X0883272Y0543946*
X088323Y0543914*
X0883192Y0543879*
X0883155Y0543841*
X0883121Y0543801*
X0883091Y0543759*
X0883063Y0543715*
X0883038Y0543668*
X0883017Y054362*
X0882999Y0543571*
X0882985Y0543521*
X0882974Y054347*
X0882967Y0543418*
X0882963Y0543366*
Y0543313*
X0882967Y0543261*
X0882974Y0543209*
X0882985Y0543158*
X0882999Y0543108*
X0883017Y0543059*
X0883038Y0543011*
X0883063Y0542965*
X0883091Y054292*
X0883121Y0542878*
X0883155Y0542838*
X0883192Y05428*
X088323Y0542765*
X0883272Y0542733*
X0883315Y0542703*
X088336Y0542677*
X0883407Y0542654*
X0883456Y0542635*
X0883506Y0542619*
X0883557Y0542606*
X0883608Y0542597*
X088366Y0542591*
X0883713Y054259*
X08852Y054184D02*
D01*
X0885198Y0541892*
X0885192Y0541944*
X0885183Y0541995*
X088517Y0542046*
X0885154Y0542096*
X0885135Y0542145*
X0885112Y0542192*
X0885086Y0542237*
X0885056Y054228*
X0885024Y0542322*
X0884989Y054236*
X0884951Y0542397*
X0884911Y0542431*
X0884869Y0542461*
X0884825Y0542489*
X0884778Y0542514*
X088473Y0542535*
X0884681Y0542553*
X0884631Y0542567*
X088458Y0542578*
X0884528Y0542585*
X0884476Y0542589*
X088445Y054259*
X0864498Y055256D02*
D01*
X0865035Y0553137*
X0865531Y055375*
X0865982Y0554397*
X0866388Y0555073*
X0866746Y0555776*
X0867053Y0556503*
X0867309Y0557249*
X0867513Y0558011*
X0867662Y0558785*
X0867758Y0559568*
X0867798Y0560356*
X08678Y0560542*
X0864486Y0552547D02*
D01*
X0864488Y0552549*
X0864491Y0552551*
X0864493Y0552554*
X0864495Y0552557*
X0864498Y055256*
X085259Y0540652D02*
D01*
X0852566Y0540626*
X0852544Y0540599*
X0852524Y054057*
X0852506Y054054*
X085249Y0540509*
X0852476Y0540477*
X0852465Y0540444*
X0852456Y0540411*
X0852449Y0540376*
X0852445Y0540342*
X0852443Y0540307*
X0852443Y0540272*
X0852444Y0540261*
X0849722Y0537901D02*
D01*
X0849876Y0537873*
X0850032Y0537855*
X0850189Y0537849*
X0850346Y0537854*
X0850502Y053787*
X0850657Y0537896*
X085081Y0537933*
X0850959Y0537981*
X0851105Y053804*
X0851247Y0538108*
X0851383Y0538186*
X0851514Y0538273*
X0851638Y0538369*
X0851755Y0538474*
X0851865Y0538586*
X0851966Y0538706*
X0852059Y0538833*
X0852143Y0538965*
X0852218Y0539104*
X0852282Y0539247*
X0852336Y0539394*
X085238Y0539545*
X0852414Y0539699*
X0852436Y0539854*
X0852448Y0540011*
X0852449Y0540168*
X0852444Y0540261*
X0863571Y0553471D02*
D01*
X0864047Y0553981*
X0864486Y0554523*
X0864886Y0555095*
X0865246Y0555693*
X0865562Y0556315*
X0865835Y0556958*
X0866062Y0557618*
X0866243Y0558292*
X0866376Y0558977*
X0866461Y055967*
X0866498Y0560367*
X08665Y0560542*
X0837111Y05583D02*
D01*
X08371Y055825*
X083709Y05582*
X083708Y055815*
X0837071Y05581*
X0837062Y055805*
X083615Y05509D02*
D01*
X0836202Y0550901*
X0836254Y0550907*
X0836305Y0550916*
X0836356Y0550929*
X0836406Y0550945*
X0836455Y0550964*
X0836502Y0550987*
X0836547Y0551013*
X083659Y0551043*
X0836632Y0551075*
X083667Y055111*
X0836707Y0551148*
X0836741Y0551188*
X0836771Y055123*
X0836799Y0551275*
X0836824Y0551321*
X0836845Y0551369*
X0836863Y0551418*
X0836877Y0551468*
X0836888Y0551519*
X0836895Y0551571*
X0836899Y0551623*
X08369Y055165*
X083615Y05509D02*
D01*
X0836097Y0550898*
X0836045Y0550892*
X0835994Y0550883*
X0835943Y055087*
X0835893Y0550854*
X0835844Y0550835*
X0835797Y0550812*
X0835752Y0550786*
X0835709Y0550756*
X0835667Y0550724*
X0835629Y0550689*
X0835592Y0550651*
X0835558Y0550611*
X0835528Y0550569*
X08355Y0550525*
X0835475Y0550478*
X0835454Y055043*
X0835436Y0550381*
X0835422Y0550331*
X0835411Y055028*
X0835404Y0550228*
X08354Y0550176*
Y0550123*
X0835404Y0550071*
X0835411Y0550019*
X0835422Y0549968*
X0835436Y0549918*
X0835454Y0549869*
X0835475Y0549821*
X08355Y0549775*
X0835528Y054973*
X0835558Y0549688*
X0835592Y0549648*
X0835629Y054961*
X0835667Y0549575*
X0835709Y0549543*
X0835752Y0549513*
X0835797Y0549487*
X0835844Y0549464*
X0835893Y0549445*
X0835943Y0549429*
X0835994Y0549416*
X0836045Y0549407*
X0836097Y0549401*
X083615Y05494*
X08369Y05479D02*
D01*
X0836952Y0547901*
X0837004Y0547907*
X0837055Y0547916*
X0837106Y0547929*
X0837156Y0547945*
X0837205Y0547964*
X0837252Y0547987*
X0837297Y0548013*
X083734Y0548043*
X0837382Y0548075*
X083742Y054811*
X0837457Y0548148*
X0837491Y0548188*
X0837521Y054823*
X0837549Y0548275*
X0837574Y0548321*
X0837595Y0548369*
X0837613Y0548418*
X0837627Y0548468*
X0837638Y0548519*
X0837645Y0548571*
X0837649Y0548623*
Y0548676*
X0837645Y0548728*
X0837638Y054878*
X0837627Y0548831*
X0837613Y0548881*
X0837595Y054893*
X0837574Y0548978*
X0837549Y0549025*
X0837521Y0549069*
X0837491Y0549111*
X0837457Y0549151*
X083742Y0549189*
X0837382Y0549224*
X083734Y0549256*
X0837297Y0549286*
X0837252Y0549312*
X0837205Y0549335*
X0837156Y0549354*
X0837106Y054937*
X0837055Y0549383*
X0837004Y0549392*
X0836952Y0549398*
X08369Y05494*
X0835853Y05479D02*
D01*
X08358Y0547898*
X0835748Y0547892*
X0835697Y0547883*
X0835646Y054787*
X0835596Y0547854*
X0835547Y0547835*
X08355Y0547812*
X0835455Y0547786*
X0835412Y0547756*
X083537Y0547724*
X0835332Y0547689*
X0835295Y0547651*
X0835261Y0547611*
X0835231Y0547569*
X0835203Y0547525*
X0835178Y0547478*
X0835157Y054743*
X0835139Y0547381*
X0835125Y0547331*
X0835114Y054728*
X0835107Y0547228*
X0835103Y0547176*
Y0547123*
X0835107Y0547071*
X0835114Y0547019*
X0835125Y0546968*
X0835139Y0546918*
X0835157Y0546869*
X0835178Y0546821*
X0835203Y0546775*
X0835231Y054673*
X0835261Y0546688*
X0835295Y0546648*
X0835332Y054661*
X083537Y0546575*
X0835412Y0546543*
X0835455Y0546513*
X08355Y0546487*
X0835547Y0546464*
X0835596Y0546445*
X0835646Y0546429*
X0835697Y0546416*
X0835748Y0546407*
X08358Y0546401*
X0835853Y05464*
X08369Y054565D02*
D01*
X0836898Y0545702*
X0836892Y0545754*
X0836883Y0545805*
X083687Y0545856*
X0836854Y0545906*
X0836835Y0545955*
X0836812Y0546002*
X0836786Y0546047*
X0836756Y054609*
X0836724Y0546132*
X0836689Y054617*
X0836651Y0546207*
X0836611Y0546241*
X0836569Y0546271*
X0836525Y0546299*
X0836478Y0546324*
X083643Y0546345*
X0836381Y0546363*
X0836331Y0546377*
X083628Y0546388*
X0836228Y0546395*
X0836176Y0546399*
X083615Y05464*
X0839829Y0563329D02*
D01*
X0839352Y0562818*
X0838913Y0562276*
X0838513Y0561704*
X0838153Y0561106*
X0837837Y0560484*
X0837564Y0559841*
X0837337Y0559181*
X0837156Y0558507*
X0837111Y05583*
X0835092Y0543006D02*
D01*
X0835123Y054288*
X0835164Y0542758*
X0835213Y0542638*
X083527Y0542522*
X0835335Y0542411*
X0835408Y0542304*
X0835488Y0542203*
X0835575Y0542107*
X0835668Y0542018*
X0835768Y0541936*
X0835873Y054186*
X0835983Y0541792*
X0836097Y0541732*
X0836215Y054168*
X0836337Y0541637*
X0836461Y0541602*
X0836588Y0541576*
X0836716Y0541558*
X0836844Y054155*
X0836974Y0541551*
X0837102Y054156*
X083723Y0541579*
X0837356Y0541606*
X083748Y0541643*
X0837601Y0541687*
X0837719Y0541741*
X0837833Y0541802*
X0837942Y0541871*
X0838046Y0541947*
X0838145Y0542031*
X0838237Y0542121*
X0838323Y0542217*
X0838402Y054232*
X0838474Y0542427*
X0838538Y0542539*
X0838594Y0542656*
X0838642Y0542776*
X0838681Y0542899*
X0838711Y0543024*
X0838733Y0543151*
X0838746Y054328*
X083875Y0543386*
X0835092Y0543006D02*
D01*
X0835083Y0543039*
X0835072Y0543073*
X0835059Y0543105*
X0835043Y0543136*
X0835026Y0543166*
X0835006Y0543195*
X0834984Y0543223*
X0834961Y0543249*
X0834936Y0543273*
X0834909Y0543295*
X0834881Y0543315*
X0834851Y0543334*
X083482Y054335*
X0834788Y0543364*
X0834755Y0543376*
X0834722Y0543385*
X0834687Y0543393*
X0834653Y0543397*
X0834618Y05434*
X0834601Y05434*
X0838792Y0543583D02*
D01*
X0838779Y054355*
X0838768Y0543517*
X083876Y0543483*
X0838754Y0543448*
X083875Y0543414*
X083875Y0543386*
X0841729Y0561829D02*
D01*
X0841252Y0561318*
X0840813Y0560776*
X0840413Y0560204*
X0840053Y0559606*
X0839737Y0558984*
X0839464Y0558341*
X0839237Y0557681*
X0839056Y0557007*
X0838923Y0556322*
X0838838Y0555629*
X0838801Y0554932*
X08388Y0554758*
X088Y05978D02*
D01*
X0880271Y0597546*
X088056Y0597312*
X0880864Y0597099*
X0881182Y0596908*
X0881513Y0596739*
X0881855Y0596594*
X0882207Y0596473*
X0882565Y0596377*
X088293Y0596306*
X0883299Y0596261*
X088367Y0596242*
X0883763Y0596241*
X0889675Y0593825D02*
D01*
X0889253Y0594217*
X0888806Y059458*
X0888334Y059491*
X0887841Y0595206*
X0887328Y0595468*
X0886798Y0595693*
X0886253Y059588*
X0885697Y0596029*
X0885132Y0596139*
X088456Y0596209*
X0883985Y0596239*
X0883841Y0596241*
X0888605Y0596795D02*
D01*
X0888196Y0597176*
X0887761Y0597528*
X0887303Y0597848*
X0886824Y0598136*
X0886326Y059839*
X0885811Y0598609*
X0885282Y0598791*
X0884742Y0598935*
X0884194Y0599042*
X0883639Y059911*
X088308Y0599139*
X0882941Y0599141*
X0901Y0578358D02*
D01*
X0900975Y0579055*
X0900902Y0579749*
X0900781Y0580437*
X0900612Y0581114*
X0900396Y0581778*
X0900135Y0582425*
X0899829Y0583052*
X089948Y0583657*
X089909Y0584235*
X089866Y0584785*
X0898193Y0585304*
X0898071Y0585429*
X09023Y0578958D02*
D01*
X0902275Y0579655*
X0902202Y0580349*
X0902081Y0581037*
X0901912Y0581714*
X0901696Y0582378*
X0901435Y0583025*
X0901129Y0583652*
X090078Y0584257*
X090039Y0584835*
X089996Y0585385*
X0899493Y0585904*
X0899371Y0586029*
X0901Y054245D02*
D01*
X0900998Y0542502*
X0900992Y0542554*
X0900983Y0542605*
X090097Y0542656*
X0900954Y0542706*
X0900935Y0542755*
X0900912Y0542802*
X0900886Y0542847*
X0900856Y054289*
X0900824Y0542932*
X0900789Y054297*
X0900751Y0543007*
X0900711Y0543041*
X0900669Y0543071*
X0900625Y0543099*
X0900578Y0543124*
X090053Y0543145*
X0900481Y0543163*
X0900431Y0543177*
X090038Y0543188*
X0900328Y0543195*
X0900276Y0543199*
X090025Y05432*
X0899788Y05447D02*
D01*
X0899735Y0544698*
X0899683Y0544692*
X0899632Y0544683*
X0899581Y054467*
X0899531Y0544654*
X0899482Y0544635*
X0899435Y0544612*
X089939Y0544586*
X0899347Y0544556*
X0899305Y0544524*
X0899267Y0544489*
X089923Y0544451*
X0899196Y0544411*
X0899166Y0544369*
X0899138Y0544325*
X0899113Y0544278*
X0899092Y054423*
X0899074Y0544181*
X089906Y0544131*
X0899049Y054408*
X0899042Y0544028*
X0899038Y0543976*
Y0543923*
X0899042Y0543871*
X0899049Y0543819*
X089906Y0543768*
X0899074Y0543718*
X0899092Y0543669*
X0899113Y0543621*
X0899138Y0543575*
X0899166Y054353*
X0899196Y0543488*
X089923Y0543448*
X0899267Y054341*
X0899305Y0543375*
X0899347Y0543343*
X089939Y0543313*
X0899435Y0543287*
X0899482Y0543264*
X0899531Y0543245*
X0899581Y0543229*
X0899632Y0543216*
X0899683Y0543207*
X0899735Y0543201*
X0899788Y05432*
X090025Y05447D02*
D01*
X0900302Y0544701*
X0900354Y0544707*
X0900405Y0544716*
X0900456Y0544729*
X0900506Y0544745*
X0900555Y0544764*
X0900602Y0544787*
X0900647Y0544813*
X090069Y0544843*
X0900732Y0544875*
X090077Y054491*
X0900807Y0544948*
X0900841Y0544988*
X0900871Y054503*
X0900899Y0545075*
X0900924Y0545121*
X0900945Y0545169*
X0900963Y0545218*
X0900977Y0545268*
X0900988Y0545319*
X0900995Y0545371*
X0900999Y0545423*
Y0545476*
X0900995Y0545528*
X0900988Y054558*
X0900977Y0545631*
X0900963Y0545681*
X0900945Y054573*
X0900924Y0545778*
X0900899Y0545825*
X0900871Y0545869*
X0900841Y0545911*
X0900807Y0545951*
X090077Y0545989*
X0900732Y0546024*
X090069Y0546056*
X0900647Y0546086*
X0900602Y0546112*
X0900555Y0546135*
X0900506Y0546154*
X0900456Y054617*
X0900405Y0546183*
X0900354Y0546192*
X0900302Y0546198*
X090025Y05462*
X0899643Y05477D02*
D01*
X089959Y0547698*
X0899538Y0547692*
X0899487Y0547683*
X0899436Y054767*
X0899386Y0547654*
X0899337Y0547635*
X089929Y0547612*
X0899245Y0547586*
X0899202Y0547556*
X089916Y0547524*
X0899122Y0547489*
X0899085Y0547451*
X0899051Y0547411*
X0899021Y0547369*
X0898993Y0547325*
X0898968Y0547278*
X0898947Y054723*
X0898929Y0547181*
X0898915Y0547131*
X0898904Y054708*
X0898897Y0547028*
X0898893Y0546976*
Y0546923*
X0898897Y0546871*
X0898904Y0546819*
X0898915Y0546768*
X0898929Y0546718*
X0898947Y0546669*
X0898968Y0546621*
X0898993Y0546575*
X0899021Y054653*
X0899051Y0546488*
X0899085Y0546448*
X0899122Y054641*
X089916Y0546375*
X0899202Y0546343*
X0899245Y0546313*
X089929Y0546287*
X0899337Y0546264*
X0899386Y0546245*
X0899436Y0546229*
X0899487Y0546216*
X0899538Y0546207*
X089959Y0546201*
X0899643Y05462*
X090025Y05477D02*
D01*
X0900302Y0547701*
X0900354Y0547707*
X0900405Y0547716*
X0900456Y0547729*
X0900506Y0547745*
X0900555Y0547764*
X0900602Y0547787*
X0900647Y0547813*
X090069Y0547843*
X0900732Y0547875*
X090077Y054791*
X0900807Y0547948*
X0900841Y0547988*
X0900871Y054803*
X0900899Y0548075*
X0900924Y0548121*
X0900945Y0548169*
X0900963Y0548218*
X0900977Y0548268*
X0900988Y0548319*
X0900995Y0548371*
X0900999Y0548423*
Y0548476*
X0900995Y0548528*
X0900988Y054858*
X0900977Y0548631*
X0900963Y0548681*
X0900945Y054873*
X0900924Y0548778*
X0900899Y0548825*
X0900871Y0548869*
X0900841Y0548911*
X0900807Y0548951*
X090077Y0548989*
X0900732Y0549024*
X090069Y0549056*
X0900647Y0549086*
X0900602Y0549112*
X0900555Y0549135*
X0900506Y0549154*
X0900456Y054917*
X0900405Y0549183*
X0900354Y0549192*
X0900302Y0549198*
X090025Y05492*
X0899643Y05507D02*
D01*
X089959Y0550698*
X0899538Y0550692*
X0899487Y0550683*
X0899436Y055067*
X0899386Y0550654*
X0899337Y0550635*
X089929Y0550612*
X0899245Y0550586*
X0899202Y0550556*
X089916Y0550524*
X0899122Y0550489*
X0899085Y0550451*
X0899051Y0550411*
X0899021Y0550369*
X0898993Y0550325*
X0898968Y0550278*
X0898947Y055023*
X0898929Y0550181*
X0898915Y0550131*
X0898904Y055008*
X0898897Y0550028*
X0898893Y0549976*
Y0549923*
X0898897Y0549871*
X0898904Y0549819*
X0898915Y0549768*
X0898929Y0549718*
X0898947Y0549669*
X0898968Y0549621*
X0898993Y0549575*
X0899021Y054953*
X0899051Y0549488*
X0899085Y0549448*
X0899122Y054941*
X089916Y0549375*
X0899202Y0549343*
X0899245Y0549313*
X089929Y0549287*
X0899337Y0549264*
X0899386Y0549245*
X0899436Y0549229*
X0899487Y0549216*
X0899538Y0549207*
X089959Y0549201*
X0899643Y05492*
X090025Y05507D02*
D01*
X0900302Y0550701*
X0900354Y0550707*
X0900405Y0550716*
X0900456Y0550729*
X0900506Y0550745*
X0900555Y0550764*
X0900602Y0550787*
X0900647Y0550813*
X090069Y0550843*
X0900732Y0550875*
X090077Y055091*
X0900807Y0550948*
X0900841Y0550988*
X0900871Y055103*
X0900899Y0551075*
X0900924Y0551121*
X0900945Y0551169*
X0900963Y0551218*
X0900977Y0551268*
X0900988Y0551319*
X0900995Y0551371*
X0900999Y0551423*
X0901Y055145*
X0872313Y0546623D02*
D01*
X0872365Y0546624*
X0872417Y054663*
X0872468Y0546639*
X0872519Y0546652*
X0872569Y0546668*
X0872618Y0546687*
X0872665Y054671*
X087271Y0546736*
X0872753Y0546766*
X0872795Y0546798*
X0872833Y0546833*
X087287Y0546871*
X0872904Y0546911*
X0872934Y0546953*
X0872962Y0546998*
X0872987Y0547044*
X0873006Y0547087*
X0870751Y0546623D02*
D01*
X0870698Y0546621*
X0870646Y0546615*
X0870595Y0546606*
X0870544Y0546593*
X0870494Y0546577*
X0870445Y0546558*
X0870398Y0546535*
X0870353Y0546509*
X087031Y0546479*
X0870268Y0546447*
X087023Y0546412*
X0870193Y0546374*
X0870159Y0546334*
X0870129Y0546292*
X0870101Y0546248*
X0870076Y0546201*
X0870055Y0546153*
X0870037Y0546104*
X0870023Y0546054*
X0870012Y0546003*
X0870005Y0545951*
X0870001Y0545899*
Y0545846*
X0870005Y0545794*
X0870012Y0545742*
X0870023Y0545691*
X0870037Y0545641*
X0870055Y0545592*
X0870076Y0545544*
X0870101Y0545498*
X0870129Y0545453*
X0870159Y0545411*
X0870193Y0545371*
X087023Y0545333*
X0870268Y0545298*
X087031Y0545266*
X0870353Y0545236*
X0870398Y054521*
X0870445Y0545187*
X0870494Y0545168*
X0870544Y0545152*
X0870595Y0545139*
X0870646Y054513*
X0870698Y0545124*
X0870751Y0545123*
X087265Y0543623D02*
D01*
X0872702Y0543624*
X0872754Y054363*
X0872805Y0543639*
X0872856Y0543652*
X0872906Y0543668*
X0872955Y0543687*
X0873002Y054371*
X0873047Y0543736*
X087309Y0543766*
X0873132Y0543798*
X087317Y0543833*
X0873207Y0543871*
X0873241Y0543911*
X0873271Y0543953*
X0873299Y0543998*
X0873324Y0544044*
X0873345Y0544092*
X0873363Y0544141*
X0873377Y0544191*
X0873388Y0544242*
X0873395Y0544294*
X0873399Y0544346*
Y0544399*
X0873395Y0544451*
X0873388Y0544503*
X0873377Y0544554*
X0873363Y0544604*
X0873345Y0544653*
X0873324Y0544701*
X0873299Y0544748*
X0873271Y0544792*
X0873241Y0544834*
X0873207Y0544874*
X087317Y0544912*
X0873132Y0544947*
X087309Y0544979*
X0873047Y0545009*
X0873002Y0545035*
X0872955Y0545058*
X0872906Y0545077*
X0872856Y0545093*
X0872805Y0545106*
X0872754Y0545115*
X0872702Y0545121*
X087265Y0545123*
X086934Y0543623D02*
D01*
X0869287Y0543621*
X0869235Y0543615*
X0869184Y0543606*
X0869133Y0543593*
X0869083Y0543577*
X0869034Y0543558*
X0868987Y0543535*
X0868942Y0543509*
X0868899Y0543479*
X0868857Y0543447*
X0868819Y0543412*
X0868782Y0543374*
X0868748Y0543334*
X0868718Y0543292*
X086869Y0543248*
X0868665Y0543201*
X0868644Y0543153*
X0868626Y0543104*
X0868612Y0543054*
X0868601Y0543003*
X0868594Y0542951*
X086859Y0542899*
Y0542846*
X0868594Y0542794*
X0868601Y0542742*
X0868612Y0542691*
X0868626Y0542641*
X0868644Y0542592*
X0868665Y0542544*
X086869Y0542498*
X0868718Y0542453*
X0868748Y0542411*
X0868782Y0542371*
X0868819Y0542333*
X0868857Y0542298*
X0868899Y0542266*
X0868942Y0542236*
X0868987Y054221*
X0869034Y0542187*
X0869083Y0542168*
X0869133Y0542152*
X0869184Y0542139*
X0869235Y054213*
X0869287Y0542124*
X086934Y0542123*
X0870534Y0541087D02*
D01*
X0870552Y0541136*
X0870567Y0541186*
X0870578Y0541237*
X0870585Y0541289*
X087059Y0541341*
X087059Y0541393*
X0870587Y0541445*
X087058Y0541497*
X0870569Y0541548*
X0870555Y0541599*
X0870538Y0541648*
X0870517Y0541696*
X0870493Y0541743*
X0870465Y0541787*
X0870435Y054183*
X0870401Y054187*
X0870365Y0541908*
X0870327Y0541943*
X0870286Y0541976*
X0870242Y0542005*
X0870197Y0542032*
X0870151Y0542055*
X0870102Y0542075*
X0870052Y0542092*
X0870002Y0542105*
X086995Y0542114*
X0869898Y054212*
X0869846Y0542122*
X0869841Y0542123*
X0870471Y0540971D02*
D01*
X0870476Y0540976*
X0870481Y0540981*
X0870486Y0540986*
X0870492Y0540992*
X0870497Y0540997*
X0870497Y0540998*
X085738Y0548341D02*
D01*
X0857418Y0548305*
X0857458Y0548272*
X0857501Y0548242*
X0857546Y0548215*
X0857593Y0548191*
X0857641Y0548171*
X085769Y0548154*
X0857741Y054814*
X0857792Y054813*
X0857844Y0548124*
X0857896Y0548121*
X0857949Y0548122*
X0858001Y0548127*
X0858053Y0548135*
X0858103Y0548147*
X0858154Y0548162*
X0858202Y0548181*
X085825Y0548203*
X0858296Y0548228*
X0858339Y0548257*
X0858381Y0548288*
X0858421Y0548322*
X0858441Y0548341*
X0857317Y0548404D02*
D01*
X0857278Y0548439*
X0857238Y0548472*
X0857195Y0548502*
X085715Y0548529*
X0857103Y0548553*
X0857055Y0548573*
X0857006Y054859*
X0856955Y0548604*
X0856904Y0548614*
X0856852Y054862*
X08568Y0548623*
X0856747Y0548622*
X0856695Y0548617*
X0856643Y0548609*
X0856593Y0548597*
X0856542Y0548582*
X0856494Y0548563*
X0856446Y0548541*
X08564Y0548516*
X0856357Y0548487*
X0856315Y0548456*
X0856275Y0548422*
X0856256Y0548404*
D01*
X085622Y0548365*
X0856187Y0548325*
X0856157Y0548282*
X085613Y0548237*
X0856106Y054819*
X0856086Y0548142*
X0856069Y0548093*
X0856055Y0548042*
X0856045Y0547991*
X0856039Y0547939*
X0856036Y0547887*
X0856037Y0547834*
X0856042Y0547782*
X085605Y054773*
X0856062Y054768*
X0856077Y0547629*
X0856096Y0547581*
X0856118Y0547533*
X0856143Y0547487*
X0856172Y0547444*
X0856203Y0547402*
X0856237Y0547362*
X0856256Y0547343*
X0856319Y0546219D02*
D01*
X0856354Y0546257*
X0856387Y0546297*
X0856417Y054634*
X0856444Y0546385*
X0856468Y0546432*
X0856488Y054648*
X0856505Y0546529*
X0856519Y054658*
X0856529Y0546631*
X0856535Y0546683*
X0856538Y0546735*
X0856537Y0546788*
X0856532Y054684*
X0856524Y0546892*
X0856512Y0546942*
X0856497Y0546993*
X0856478Y0547041*
X0856456Y0547089*
X0856431Y0547135*
X0856402Y0547178*
X0856371Y054722*
X0856337Y054726*
X0856319Y054728*
X0855259Y0546219D02*
D01*
X0855297Y0546183*
X0855337Y054615*
X085538Y054612*
X0855425Y0546093*
X0855472Y0546069*
X085552Y0546049*
X0855569Y0546032*
X085562Y0546018*
X0855671Y0546008*
X0855723Y0546002*
X0855775Y0545999*
X0855828Y0546*
X085588Y0546005*
X0855932Y0546013*
X0855982Y0546025*
X0856033Y054604*
X0856081Y0546059*
X0856129Y0546081*
X0856175Y0546106*
X0856218Y0546135*
X085626Y0546166*
X08563Y05462*
X0856319Y0546219*
X0854693Y0546785D02*
D01*
X0854654Y054682*
X0854614Y0546853*
X0854571Y0546883*
X0854526Y054691*
X0854479Y0546934*
X0854431Y0546954*
X0854382Y0546971*
X0854331Y0546985*
X085428Y0546995*
X0854228Y0547001*
X0854176Y0547004*
X0854123Y0547003*
X0854071Y0546998*
X0854019Y054699*
X0853969Y0546978*
X0853918Y0546963*
X085387Y0546944*
X0853822Y0546922*
X0853776Y0546897*
X0853733Y0546868*
X0853691Y0546837*
X0853651Y0546803*
X0853632Y0546785*
D01*
X0853596Y0546746*
X0853563Y0546706*
X0853533Y0546663*
X0853506Y0546618*
X0853482Y0546571*
X0853462Y0546523*
X0853445Y0546474*
X0853431Y0546423*
X0853421Y0546372*
X0853415Y054632*
X0853412Y0546268*
X0853413Y0546215*
X0853418Y0546163*
X0853426Y0546111*
X0853438Y0546061*
X0853453Y054601*
X0853472Y0545962*
X0853494Y0545914*
X0853519Y0545868*
X0853548Y0545825*
X0853579Y0545783*
X0853613Y0545743*
X0853633Y0545724*
X0854198Y0544098D02*
D01*
X0854233Y0544136*
X0854266Y0544176*
X0854296Y0544219*
X0854323Y0544264*
X0854347Y0544311*
X0854367Y0544359*
X0854384Y0544408*
X0854398Y0544459*
X0854408Y054451*
X0854414Y0544562*
X0854417Y0544614*
X0854416Y0544667*
X0854411Y0544719*
X0854403Y0544771*
X0854391Y0544821*
X0854376Y0544872*
X0854357Y054492*
X0854335Y0544968*
X085431Y0545014*
X0854281Y0545057*
X085425Y0545099*
X0854216Y0545139*
X0854198Y0545159*
X0853137Y0544098D02*
D01*
X0853175Y0544062*
X0853215Y0544029*
X0853258Y0543999*
X0853303Y0543972*
X085335Y0543948*
X0853398Y0543928*
X0853447Y0543911*
X0853498Y0543897*
X0853549Y0543887*
X0853601Y0543881*
X0853653Y0543878*
X0853706Y0543879*
X0853758Y0543884*
X085381Y0543892*
X085386Y0543904*
X0853911Y0543919*
X0853959Y0543938*
X0854007Y054396*
X0854053Y0543985*
X0854096Y0544014*
X0854138Y0544045*
X0854178Y0544079*
X0854198Y0544098*
X0852572Y0544664D02*
D01*
X0852533Y0544699*
X0852493Y0544732*
X085245Y0544762*
X0852405Y0544789*
X0852358Y0544813*
X085231Y0544833*
X0852261Y054485*
X085221Y0544864*
X0852159Y0544874*
X0852107Y054488*
X0852055Y0544883*
X0852002Y0544882*
X085195Y0544877*
X0851898Y0544869*
X0851848Y0544857*
X0851797Y0544842*
X0851749Y0544823*
X0851701Y0544801*
X0851655Y0544776*
X0851612Y0544747*
X085157Y0544716*
X085153Y0544682*
X0851511Y0544664*
D01*
X0851475Y0544625*
X0851442Y0544585*
X0851412Y0544542*
X0851385Y0544497*
X0851361Y054445*
X0851341Y0544402*
X0851324Y0544353*
X085131Y0544302*
X08513Y0544251*
X0851294Y0544199*
X0851291Y0544147*
X0851292Y0544094*
X0851297Y0544042*
X0851305Y054399*
X0851317Y054394*
X0851332Y0543889*
X0851351Y0543841*
X0851373Y0543793*
X0851398Y0543747*
X0851427Y0543704*
X0851458Y0543662*
X0851492Y0543622*
X0851511Y0543603*
X0852077Y0541977D02*
D01*
X0852112Y0542015*
X0852145Y0542055*
X0852175Y0542098*
X0852202Y0542143*
X0852226Y054219*
X0852246Y0542238*
X0852263Y0542287*
X0852277Y0542338*
X0852287Y0542389*
X0852293Y0542441*
X0852296Y0542493*
X0852295Y0542546*
X085229Y0542598*
X0852282Y054265*
X085227Y05427*
X0852255Y0542751*
X0852236Y0542799*
X0852214Y0542847*
X0852189Y0542893*
X085216Y0542936*
X0852129Y0542978*
X0852095Y0543018*
X0852077Y0543038*
X09023Y0541779D02*
D01*
X0902301Y0541744*
X0902304Y0541709*
X090231Y0541675*
X0902319Y0541641*
X090233Y0541607*
X0902343Y0541575*
X0902358Y0541544*
X0902375Y0541514*
X0902395Y0541485*
X0902416Y0541457*
X090244Y0541431*
X0902465Y0541407*
X0902473Y0541401*
X0900479Y0537511D02*
D01*
X0900632Y0537479*
X0900788Y0537459*
X0900945Y053745*
X0901102Y0537452*
X0901259Y0537464*
X0901414Y0537488*
X0901567Y0537522*
X0901718Y0537567*
X0901865Y0537622*
X0902007Y0537688*
X0902145Y0537763*
X0902278Y0537848*
X0902404Y0537941*
X0902523Y0538043*
X0902635Y0538154*
X0902739Y0538272*
X0902834Y0538396*
X090292Y0538528*
X0902997Y0538664*
X0903065Y0538806*
X0903122Y0538953*
X0903169Y0539102*
X0903205Y0539255*
X0903231Y053941*
X0903246Y0539567*
X090325Y0539724*
X0903242Y053988*
X0903224Y0540036*
X0903195Y0540191*
X0903156Y0540343*
X0903106Y0540492*
X0903045Y0540637*
X0902975Y0540777*
X0902895Y0540912*
X0902806Y0541041*
X0902708Y0541164*
X0902601Y054128*
X0902487Y0541388*
X0902473Y0541401*
X0847292Y0538908D02*
D01*
X0847467Y0538744*
X0847653Y0538593*
X084785Y0538455*
X0848055Y0538332*
X0848269Y0538223*
X084849Y0538129*
X0848717Y0538051*
X0848948Y0537989*
X0849184Y0537943*
X0849422Y0537914*
X0849662Y0537901*
X0849722Y0537901*
X0868019Y0597319D02*
D01*
X0867869Y0597158*
X0867731Y0596988*
X0867606Y0596809*
X0867493Y0596621*
X0867393Y0596426*
X0867308Y0596224*
X0867236Y0596017*
X086718Y0595805*
X0867138Y059559*
X0867111Y0595373*
X08671Y0595154*
X08671Y05951*
X08678Y058663D02*
D01*
X0867776Y0587311*
X0867704Y0587989*
X0867586Y0588661*
X0867421Y0589322*
X086721Y0589971*
X0867134Y0590175*
X08671Y0590357D02*
D01*
X0867101Y0590322*
X0867104Y0590287*
X086711Y0590253*
X0867119Y0590219*
X086713Y0590185*
X0867134Y0590175*
X08658Y0590104D02*
D01*
X0865801Y0590069*
X0865804Y0590034*
X086581Y059*
X0865819Y0589966*
X086583Y0589932*
X0865839Y058991*
X08665Y058663D02*
D01*
X0866479Y058722*
X0866417Y0587808*
X0866314Y0588391*
X0866171Y0588964*
X0865989Y0589526*
X0865839Y058991*
X0898447Y0538353D02*
D01*
X0898593Y0538216*
X0898749Y0538089*
X0898913Y0537974*
X0899085Y0537871*
X0899264Y053778*
X0899449Y0537702*
X0899638Y0537636*
X0899832Y0537584*
X0900029Y0537546*
X0900228Y0537522*
X0900428Y0537511*
X0900479Y0537511*
X0865862Y0539738D02*
D01*
X08662Y0539422*
X086656Y0539132*
X0866939Y0538867*
X0867335Y0538629*
X0867747Y0538419*
X0867965Y0538323*
X0865859Y0539741D02*
D01*
X0865859Y053974*
X086586Y0539739*
X086586Y0539739*
X0865861Y0539738*
X0865862Y0539738*
X0870544Y05378D02*
D01*
X0870806Y0537809*
X0871066Y0537836*
X0871324Y0537882*
X0871579Y0537945*
X0871828Y0538026*
X0872071Y0538124*
X0872307Y0538239*
X0872534Y053837*
X0872751Y0538517*
X0872958Y0538678*
X0873153Y0538854*
X08732Y05389*
X0869939Y0537793D02*
D01*
X0869948Y0537794*
X0869957Y0537796*
X0869966Y0537798*
X0869975Y05378*
X0869984Y0537803*
X0868265Y0538119D02*
D01*
X0868399Y0538037*
X0868538Y0537965*
X0868683Y0537903*
X0868831Y0537851*
X0868982Y053781*
X0869136Y0537779*
X0869292Y0537759*
X0869449Y053775*
X0869606Y0537752*
X0869763Y0537765*
X0869918Y0537789*
X0869939Y0537793*
X0868085Y0538251D02*
D01*
X086821Y0538156*
X0868265Y0538119*
X0870123Y0537813D02*
D01*
X0870207Y0537808*
X0870291Y0537804*
X0870375Y0537801*
X0870459Y05378*
X0870544Y05378*
X0868085Y0538251D02*
D01*
X0868057Y0538271*
X0868027Y053829*
X0867997Y0538307*
X0867965Y0538322*
X0867965Y0538323*
X0870123Y0537813D02*
D01*
X0870088Y0537814*
X0870053Y0537812*
X0870018Y0537808*
X0869984Y0537802*
X0869984Y0537803*
X08746Y0541514D02*
D01*
X0874658Y0541866*
X0874691Y0542222*
X08747Y0542521*
X08732Y05389D02*
D01*
X0873443Y0539161*
X0873668Y0539439*
X0873873Y0539731*
X0874057Y0540038*
X087422Y0540356*
X0874359Y0540685*
X0874476Y0541023*
X0874568Y0541369*
X08746Y0541514*
X0876064Y0581945D02*
D01*
X0876042Y0581881*
X0876024Y0581816*
X0876011Y0581749*
X0876003Y0581683*
X0876Y0581615*
X0876Y05816*
D01*
X0875788Y0581373*
X0875593Y0581132*
X0875415Y0580878*
X0875256Y0580613*
X0875115Y0580337*
X0874994Y0580051*
X0874893Y0579758*
X0874813Y0579459*
X0874754Y0579155*
X0874716Y0578847*
X08747Y0578538*
X08747Y0578462*
X087653Y0582264D02*
D01*
X0876495Y0582262*
X087646Y0582259*
X0876426Y0582253*
X0876392Y0582244*
X0876358Y0582233*
X0876326Y058222*
X0876295Y0582205*
X0876265Y0582188*
X0876236Y0582168*
X0876208Y0582147*
X0876182Y0582123*
X0876158Y0582098*
X0876135Y0582071*
X0876115Y0582043*
X0876096Y0582014*
X087608Y0581983*
X0876066Y0581951*
X0876064Y0581945*
X0881568Y0539665D02*
X0882745Y0538488D01*
X0886475Y0541163D02*
D01*
X0886522Y0540886D02*
D01*
X08865Y054159D02*
Y05684D01*
Y0580188D02*
Y05684D01*
X0886589Y0580538D02*
D01*
X0886523Y0580337D02*
D01*
X0887522Y058235D02*
D01*
X08852Y0557518D02*
Y05824D01*
Y055084D02*
Y0557518D01*
X088415Y055009D02*
X088445D01*
X088415Y054859D02*
X088445D01*
X0883713Y054709D02*
X088445D01*
X0883713Y054559D02*
X088445D01*
X0883713Y054409D02*
X088445D01*
X0883713Y054259D02*
X088445D01*
X08852Y054159D02*
Y054184D01*
X085259Y0540652D02*
X0864486Y0552547D01*
X08618Y05517D02*
X0863571Y0553471D01*
X0901Y05397D02*
Y05411D01*
X08369Y0556258D02*
X0837062Y055805D01*
X08369Y055165D02*
Y0556258D01*
X083615Y05509D02*
D01*
Y05494D02*
X08369D01*
X0835853Y05479D02*
X08369D01*
X0835853Y05464D02*
X083615D01*
X08369Y05454D02*
Y054565D01*
Y05434D02*
Y05454D01*
X0835092Y0543006D02*
D01*
X0834601Y05434D02*
D01*
X08345D02*
X0834601D01*
X0838799Y0543599D02*
X08388Y05436D01*
X083875Y0543386D02*
D01*
X0838792Y0543583D02*
X0838799Y0543599D01*
X08388Y05436D02*
Y0554758D01*
X0841729Y0561829D02*
X08616Y05817D01*
X0839829Y0563329D02*
X08582Y05817D01*
X0889675Y0593825D02*
X0898071Y0585429D01*
X0883763Y0596241D02*
X0883841D01*
X0888605Y0596795D02*
X0899371Y0586029D01*
X0901Y05532D02*
Y0578358D01*
X09023Y05687D02*
Y0578958D01*
X0901Y05411D02*
Y054245D01*
X0899788Y05432D02*
X090025D01*
X0899788Y05447D02*
X090025D01*
X0899643Y05462D02*
X090025D01*
X0899643Y05477D02*
X090025D01*
X0899643Y05492D02*
X090025D01*
X0899643Y05507D02*
X090025D01*
X0901Y055145D02*
Y05532D01*
X08734Y0548042D02*
Y05599D01*
Y0548042D02*
D01*
X0873006Y0547087D02*
X08734Y0548042D01*
X0873006Y0547087D02*
D01*
X0870751Y0546623D02*
X0872313D01*
X0870751Y0545123D02*
X087265D01*
X086934Y0543623D02*
X087265D01*
X086934Y0542123D02*
X0869841D01*
X0870534Y0541087D02*
D01*
X0870497Y0540998D02*
X0870534Y0541087D01*
X0870247Y0540747D02*
X0870471Y0540971D01*
X08695Y054D02*
X0870247Y0540747D01*
X08734Y05599D02*
Y05827D01*
X0858441Y0548341D02*
X08618Y05517D01*
X085738Y0548341D02*
D01*
X0857317Y0548404D02*
X085738Y0548341D01*
X0856256Y0547343D02*
X0856319Y054728D01*
X0854693Y0546785D02*
X0855259Y0546219D01*
X0853632Y0545724D02*
X0854198Y0545159D01*
X0852572Y0544664D02*
X0853137Y0544098D01*
X0851511Y0543603D02*
X0852077Y0543038D01*
X08519Y05418D02*
X0852077Y0541977D01*
X08502Y05401D02*
X08519Y05418D01*
X09023Y0541779D02*
Y05687D01*
X0846Y05402D02*
X0847292Y0538908D01*
X0868019Y0597319D02*
X08692Y05985D01*
X08658Y0590104D02*
Y05985D01*
X08665Y0560542D02*
Y058663D01*
X08678Y0560542D02*
Y058663D01*
X08671Y0590357D02*
Y05951D01*
X0867134Y0590175D02*
D01*
X0881529Y0578529D02*
X08822Y05792D01*
X0897Y05398D02*
X0898447Y0538353D01*
X08655Y05401D02*
X0865859Y0539741D01*
X08747Y0542521D02*
Y0578462D01*
X087653Y0582264D02*
X0876568Y0582265D01*
X087657Y0582263*
G54D147*
X0784Y05275D02*
Y08705D01*
G54D155*
X1005256Y0759928D03*
X1156831Y0749298D03*
Y0589456D03*
G54D162*
X0803Y09056D03*
X07429Y09064D03*
G54D163*
X0803Y09256D03*
X07429Y09264D03*
G54D165*
X0784252Y0525984D03*
X0782283Y0529134D03*
X0784252D03*
X082219Y075881D03*
X082425Y076175D03*
X0826219Y0746781D03*
X0931933Y0683D03*
X0942941Y0687488D03*
X0755836Y0707164D03*
X09592Y08142D03*
Y07896D03*
X11568Y07218D03*
X08693Y07293D03*
X08685Y06485D03*
X0838Y08485D03*
X08375Y06945D03*
X09735Y08265D03*
X0976402Y0667004D03*
X11625Y0724D03*
X08615Y07465D03*
X08617Y06774D03*
X0993Y08125D03*
X09915Y0654D03*
X08716Y08164D03*
X08717Y08329D03*
X0918742Y06718D03*
X09188Y07974D03*
X08595Y06738D03*
X0859Y0744D03*
X08245Y0854D03*
X0829Y0692D03*
X08845Y05399D03*
X0881D03*
X0888285Y0583251D03*
X08852Y05824D03*
X0857Y07285D03*
Y06794D03*
X0825Y08265D03*
X09365Y08277D03*
X09359Y08054D03*
X1003Y0741D03*
X0854Y06759D03*
X08625Y0841D03*
X09268Y06809D03*
X09265Y0861D03*
X09797Y08239D03*
X09794Y06695D03*
X0745Y08151D03*
X07431Y08561D03*
X09482Y08107D03*
X09614Y07591D03*
X09613Y0849D03*
X09482Y08301D03*
X0953302Y0832298D03*
X09335Y08D03*
X09644Y08297D03*
X09385Y08451D03*
X09427Y08461D03*
X09349Y08452D03*
X08425Y0855D03*
X0857Y0849D03*
X09215Y0666528D03*
X0958Y06715D03*
X0901Y054D03*
X08469Y05941D03*
X08717Y07297D03*
X08933Y0729D03*
X08734Y05827D03*
X08656Y07295D03*
X08658Y05985D03*
X09885Y0657D03*
X08582Y05817D03*
X08976Y07291D03*
X08466Y07295D03*
X087657Y0582263D03*
X08822Y05792D03*
X09855Y06515D03*
X09289Y06975D03*
X07875Y07075D03*
X09383Y06875D03*
X08692Y05985D03*
X08911Y07432D03*
X08636Y07278D03*
X084Y07287D03*
X088Y05978D03*
X08441Y07286D03*
X09243Y06665D03*
X0954Y06445D03*
X0761Y07125D03*
X0771Y0654D03*
X08616Y05817D03*
X09825Y06485D03*
X08885Y07435D03*
X07745Y0713D03*
X0882941Y0599141D03*
X0957Y07947D03*
X09221Y08239D03*
X09243Y08297D03*
X08197Y06302D03*
X08196Y08204D03*
X08495Y08086D03*
X08493Y0632D03*
X08516Y07467D03*
X09333Y07267D03*
X09489Y07345D03*
X0841935Y07625D03*
X08437Y06441D03*
X084Y06971D03*
X08634Y0662D03*
X08657Y06644D03*
X08345Y05434D03*
X08369D03*
X0897Y05398D03*
X08695Y054D03*
X08655Y05401D03*
X0846Y05402D03*
X08502Y05401D03*
X0957Y0759D03*
X07875Y08605D03*
X07745Y08665D03*
X0754Y08625D03*
X07565Y086D03*
X08075Y089D03*
X08074Y064156D03*
X0805Y0639D03*
Y08875D03*
X0802Y0884D03*
X08019Y063656D03*
X07995Y0882D03*
Y0634D03*
X08225Y0851D03*
X0898354Y08755D03*
X09005Y08835D03*
X08885Y06565D03*
X0891Y0654D03*
X08265Y0651D03*
X0871Y06595D03*
X09715Y06679D03*
X0777Y0916D03*
X09495Y0909D03*
X09845Y08155D03*
X0982Y0818D03*
X0979Y08205D03*
X09293Y08348D03*
X0946Y0846D03*
X0784Y08705D03*
M02*